(kicad_pcb
	(version 20260206)
	(generator "pcbnew")
	(generator_version "10.0")
	(general
		(thickness 1.6)
		(legacy_teardrops no)
	)
	(paper "A4")
	(title_block
		(title "Bryce Canyon_SCC_16316-1_OCP.brd")
		(comment 1 "Bryce Canyon / footprints 953-960 of 1561")
	)
	(layers
		(0 "F.Cu" signal "TOP")
		(4 "In1.Cu" signal "L2GND")
		(6 "In2.Cu" signal "L3")
		(8 "In3.Cu" signal "L4VCC")
		(10 "In4.Cu" signal "L5VCC")
		(12 "In5.Cu" signal "L6")
		(14 "In6.Cu" signal "L7GND")
		(2 "B.Cu" signal "BOTTOM")
		(9 "F.Adhes" user "F.Adhesive")
		(11 "B.Adhes" user "B.Adhesive")
		(13 "F.Paste" user "Package Geometry/Pastemask Top")
		(15 "B.Paste" user "Package Geometry/Pastemask Bottom")
		(5 "F.SilkS" user "Ref Des/Silkscreen Top")
		(7 "B.SilkS" user "Ref Des/Silkscreen Bottom")
		(1 "F.Mask" user "Board Geometry/Soldermask Top")
		(3 "B.Mask" user "Board Geometry/Soldermask Bottom")
		(17 "Dwgs.User" user "User.Drawings")
		(19 "Cmts.User" user "User.Comments")
		(21 "Eco1.User" user "User.Eco1")
		(23 "Eco2.User" user "User.Eco2")
		(25 "Edge.Cuts" user "Board Geometry/Outline")
		(27 "Margin" user)
		(31 "F.CrtYd" user "Package Geometry/Place Bound Top")
		(29 "B.CrtYd" user "Package Geometry/Place Bound Bottom")
		(35 "F.Fab" user "Ref Des/Assembly Top")
		(33 "B.Fab" user "Ref Des/Assembly Bottom")
	)
	(footprint ""
		(layer "B.Cu")
		(at 136.1948 -78.0542 -90)
		(property "Reference" "C6"
			(at 0 0 90)
			(layer "B.SilkS")
			(hide yes)
			(effects
				(font
					(size 1.27 1.27)
				)
				(justify mirror)
			)
		)
		(property "Value" "SCD01U16V1KX-GP"
			(at 2.8321 -1.7399 270)
			(unlocked yes)
			(layer "B.Fab")
			(hide yes)
			(effects
				(font
					(size 1.016 1.016)
					(thickness 0.1524)
				)
				(justify mirror)
			)
		)
		(property "Device Type" "C0201H13"
			(at 2.8321 -3.2639 270)
			(unlocked yes)
			(layer "B.Fab")
			(hide yes)
			(effects
				(font
					(size 1.016 1.016)
					(thickness 0.1524)
				)
				(justify mirror)
			)
		)
		(duplicate_pad_numbers_are_jumpers no)
		(fp_rect
			(start 0.2794 0.6477)
			(end -0.2794 -0.6477)
			(stroke
				(width 0)
				(type default)
			)
			(fill no)
			(layer "B.CrtYd")
		)
		(fp_rect
			(start 0.2794 0.6477)
			(end -0.2794 -0.6477)
			(stroke
				(width 0)
				(type default)
			)
			(fill no)
			(layer "B.Fab")
		)
		(pad "1" smd custom
			(at 0 -0.2794 90)
			(size 0.0762 0.0762)
			(layers "B.Cu" "B.Mask" "B.Paste")
			(net "PHY_CONN_TO_EXP_9_DN")
			(options
				(clearance outline)
				(anchor circle)
			)
			(primitives
				(gr_poly
					(pts
						(arc
							(start 0.1524 0.127)
							(mid 0.137521 0.162921)
							(end 0.1016 0.1778)
						)
						(arc
							(start -0.1016 0.1778)
							(mid -0.137521 0.162921)
							(end -0.1524 0.127)
						)
						(arc
							(start -0.1524 -0.127)
							(mid -0.137521 -0.162921)
							(end -0.1016 -0.1778)
						)
						(arc
							(start 0.1016 -0.1778)
							(mid 0.137521 -0.162921)
							(end 0.1524 -0.127)
						)
					)
					(width 0)
					(fill yes)
				)
			)
		)
		(pad "2" smd custom
			(at 0 0.2794 90)
			(size 0.0762 0.0762)
			(layers "B.Cu" "B.Mask" "B.Paste")
			(net "PHY_CONN_TO_EXP_C_9_DN")
			(options
				(clearance outline)
				(anchor circle)
			)
			(primitives
				(gr_poly
					(pts
						(arc
							(start 0.1524 0.127)
							(mid 0.137521 0.162921)
							(end 0.1016 0.1778)
						)
						(arc
							(start -0.1016 0.1778)
							(mid -0.137521 0.162921)
							(end -0.1524 0.127)
						)
						(arc
							(start -0.1524 -0.127)
							(mid -0.137521 -0.162921)
							(end -0.1016 -0.1778)
						)
						(arc
							(start 0.1016 -0.1778)
							(mid 0.137521 -0.162921)
							(end 0.1524 -0.127)
						)
					)
					(width 0)
					(fill yes)
				)
			)
		)
	)
	(footprint ""
		(layer "B.Cu")
		(at 111.2774 -57.4802)
		(property "Reference" "C540"
			(at 0 0 0)
			(layer "B.SilkS")
			(hide yes)
			(effects
				(font
					(size 1.27 1.27)
				)
				(justify mirror)
			)
		)
		(property "Value" "SCD1U6D3V1KX-GP"
			(at 2.8321 -1.7399 0)
			(unlocked yes)
			(layer "B.Fab")
			(hide yes)
			(effects
				(font
					(size 1.016 1.016)
					(thickness 0.1524)
				)
				(justify mirror)
			)
		)
		(property "Device Type" "C0201H13"
			(at 2.8321 -3.2639 0)
			(unlocked yes)
			(layer "B.Fab")
			(hide yes)
			(effects
				(font
					(size 1.016 1.016)
					(thickness 0.1524)
				)
				(justify mirror)
			)
		)
		(duplicate_pad_numbers_are_jumpers no)
		(fp_rect
			(start 0.2794 0.6477)
			(end -0.2794 -0.6477)
			(stroke
				(width 0)
				(type default)
			)
			(fill no)
			(layer "B.CrtYd")
		)
		(fp_rect
			(start 0.2794 0.6477)
			(end -0.2794 -0.6477)
			(stroke
				(width 0)
				(type default)
			)
			(fill no)
			(layer "B.Fab")
		)
		(pad "1" smd custom
			(at 0 -0.2794 180)
			(size 0.0762 0.0762)
			(layers "B.Cu" "B.Mask" "B.Paste")
			(net "GB_VDDA")
			(options
				(clearance outline)
				(anchor circle)
			)
			(primitives
				(gr_poly
					(pts
						(arc
							(start 0.1524 0.127)
							(mid 0.137521 0.162921)
							(end 0.1016 0.1778)
						)
						(arc
							(start -0.1016 0.1778)
							(mid -0.137521 0.162921)
							(end -0.1524 0.127)
						)
						(arc
							(start -0.1524 -0.127)
							(mid -0.137521 -0.162921)
							(end -0.1016 -0.1778)
						)
						(arc
							(start 0.1016 -0.1778)
							(mid 0.137521 -0.162921)
							(end 0.1524 -0.127)
						)
					)
					(width 0)
					(fill yes)
				)
			)
		)
		(pad "2" smd custom
			(at 0 0.2794 180)
			(size 0.0762 0.0762)
			(layers "B.Cu" "B.Mask" "B.Paste")
			(net "GND")
			(options
				(clearance outline)
				(anchor circle)
			)
			(primitives
				(gr_poly
					(pts
						(arc
							(start 0.1524 0.127)
							(mid 0.137521 0.162921)
							(end 0.1016 0.1778)
						)
						(arc
							(start -0.1016 0.1778)
							(mid -0.137521 0.162921)
							(end -0.1524 0.127)
						)
						(arc
							(start -0.1524 -0.127)
							(mid -0.137521 -0.162921)
							(end -0.1016 -0.1778)
						)
						(arc
							(start 0.1016 -0.1778)
							(mid 0.137521 -0.162921)
							(end 0.1524 -0.127)
						)
					)
					(width 0)
					(fill yes)
				)
			)
		)
	)
	(footprint ""
		(layer "B.Cu")
		(at 191.135 -32.385)
		(property "Reference" "TP117"
			(at 0 0 0)
			(layer "B.SilkS")
			(hide yes)
			(effects
				(font
					(size 1.27 1.27)
				)
				(justify mirror)
			)
		)
		(property "Value" "TPAD28-2-GP"
			(at 0.0127 -1.6637 0)
			(unlocked yes)
			(layer "B.Fab")
			(hide yes)
			(effects
				(font
					(size 1.016 1.016)
					(thickness 0.1524)
				)
				(justify mirror)
			)
		)
		(property "Device Type" "TPAD28"
			(at 0.0127 -3.1877 0)
			(unlocked yes)
			(layer "B.Fab")
			(hide yes)
			(effects
				(font
					(size 1.016 1.016)
					(thickness 0.1524)
				)
				(justify mirror)
			)
		)
		(duplicate_pad_numbers_are_jumpers no)
		(fp_poly
			(pts
				(arc
					(start 0.3556 0)
					(mid -0.3556 0)
					(end 0.3556 0)
				)
			)
			(stroke
				(width 0)
				(type default)
			)
			(fill no)
			(layer "B.CrtYd")
		)
		(fp_poly
			(pts
				(arc
					(start 0.6096 0)
					(mid -0.6096 0)
					(end 0.6096 0)
				)
			)
			(stroke
				(width 0)
				(type default)
			)
			(fill no)
			(layer "B.Fab")
		)
		(pad "1" smd circle
			(at 0 0 180)
			(size 0.7112 0.7112)
			(layers "B.Cu" "B.Mask" "B.Paste")
			(net "UART_SERCLK")
		)
	)
	(footprint ""
		(layer "B.Cu")
		(at 124.82703 -88.559132 180)
		(property "Reference" "R127"
			(at 0 0 0)
			(layer "B.SilkS")
			(hide yes)
			(effects
				(font
					(size 1.27 1.27)
				)
				(justify mirror)
			)
		)
		(property "Value" "4K7R2F-GP"
			(at -0.064008 -3.993896 180)
			(unlocked yes)
			(layer "B.Fab")
			(hide yes)
			(effects
				(font
					(size 1.016 1.016)
					(thickness 0.1524)
				)
				(justify mirror)
			)
		)
		(property "Device Type" "R402H16"
			(at -0.064008 -5.517896 180)
			(unlocked yes)
			(layer "B.Fab")
			(hide yes)
			(effects
				(font
					(size 1.016 1.016)
					(thickness 0.1524)
				)
				(justify mirror)
			)
		)
		(duplicate_pad_numbers_are_jumpers no)
		(fp_line
			(start 0.508 -0.9398)
			(end 0.508 0.9398)
			(stroke
				(width 0.1524)
				(type default)
			)
			(layer "B.SilkS")
		)
		(fp_line
			(start -0.508 -0.9398)
			(end 0.508 -0.9398)
			(stroke
				(width 0.1524)
				(type default)
			)
			(layer "B.SilkS")
		)
		(fp_rect
			(start 0.508 0.9398)
			(end -0.508 -0.9398)
			(stroke
				(width 0)
				(type default)
			)
			(fill no)
			(layer "B.CrtYd")
		)
		(fp_rect
			(start 0.508 0.9398)
			(end -0.508 -0.9398)
			(stroke
				(width 0)
				(type default)
			)
			(fill no)
			(layer "B.Fab")
		)
		(pad "1" smd custom
			(at 0 -0.4445)
			(size 0.1397 0.1397)
			(layers "B.Cu" "B.Mask" "B.Paste")
			(net "USB_DIR")
			(options
				(clearance outline)
				(anchor circle)
			)
			(primitives
				(gr_poly
					(pts
						(arc
							(start -0.1778 0.2794)
							(mid -0.249642 0.249642)
							(end -0.2794 0.1778)
						)
						(arc
							(start -0.2794 -0.1778)
							(mid -0.249642 -0.249642)
							(end -0.1778 -0.2794)
						)
						(arc
							(start 0.1778 -0.2794)
							(mid 0.249642 -0.249642)
							(end 0.2794 -0.1778)
						)
						(arc
							(start 0.2794 0.1778)
							(mid 0.249642 0.249642)
							(end 0.1778 0.2794)
						)
					)
					(width 0)
					(fill yes)
				)
			)
		)
		(pad "2" smd custom
			(at 0 0.4445)
			(size 0.1397 0.1397)
			(layers "B.Cu" "B.Mask" "B.Paste")
			(net "GND")
			(options
				(clearance outline)
				(anchor circle)
			)
			(primitives
				(gr_poly
					(pts
						(arc
							(start -0.1778 0.2794)
							(mid -0.249642 0.249642)
							(end -0.2794 0.1778)
						)
						(arc
							(start -0.2794 -0.1778)
							(mid -0.249642 -0.249642)
							(end -0.1778 -0.2794)
						)
						(arc
							(start 0.1778 -0.2794)
							(mid 0.249642 -0.249642)
							(end 0.2794 -0.1778)
						)
						(arc
							(start 0.2794 0.1778)
							(mid 0.249642 0.249642)
							(end 0.1778 0.2794)
						)
					)
					(width 0)
					(fill yes)
				)
			)
		)
	)
	(footprint ""
		(layer "B.Cu")
		(at 116.713 -66.3575)
		(property "Reference" "C167"
			(at 0 0 0)
			(layer "B.SilkS")
			(hide yes)
			(effects
				(font
					(size 1.27 1.27)
				)
				(justify mirror)
			)
		)
		(property "Value" "SCD1U6D3V1KX-GP"
			(at 2.8321 -1.7399 0)
			(unlocked yes)
			(layer "B.Fab")
			(hide yes)
			(effects
				(font
					(size 1.016 1.016)
					(thickness 0.1524)
				)
				(justify mirror)
			)
		)
		(property "Device Type" "C0201H13"
			(at 2.8321 -3.2639 0)
			(unlocked yes)
			(layer "B.Fab")
			(hide yes)
			(effects
				(font
					(size 1.016 1.016)
					(thickness 0.1524)
				)
				(justify mirror)
			)
		)
		(duplicate_pad_numbers_are_jumpers no)
		(fp_rect
			(start 0.2794 0.6477)
			(end -0.2794 -0.6477)
			(stroke
				(width 0)
				(type default)
			)
			(fill no)
			(layer "B.CrtYd")
		)
		(fp_rect
			(start 0.2794 0.6477)
			(end -0.2794 -0.6477)
			(stroke
				(width 0)
				(type default)
			)
			(fill no)
			(layer "B.Fab")
		)
		(pad "1" smd custom
			(at 0 -0.2794 180)
			(size 0.0762 0.0762)
			(layers "B.Cu" "B.Mask" "B.Paste")
			(net "P0V9")
			(options
				(clearance outline)
				(anchor circle)
			)
			(primitives
				(gr_poly
					(pts
						(arc
							(start 0.1524 0.127)
							(mid 0.137521 0.162921)
							(end 0.1016 0.1778)
						)
						(arc
							(start -0.1016 0.1778)
							(mid -0.137521 0.162921)
							(end -0.1524 0.127)
						)
						(arc
							(start -0.1524 -0.127)
							(mid -0.137521 -0.162921)
							(end -0.1016 -0.1778)
						)
						(arc
							(start 0.1016 -0.1778)
							(mid 0.137521 -0.162921)
							(end 0.1524 -0.127)
						)
					)
					(width 0)
					(fill yes)
				)
			)
		)
		(pad "2" smd custom
			(at 0 0.2794 180)
			(size 0.0762 0.0762)
			(layers "B.Cu" "B.Mask" "B.Paste")
			(net "GND")
			(options
				(clearance outline)
				(anchor circle)
			)
			(primitives
				(gr_poly
					(pts
						(arc
							(start 0.1524 0.127)
							(mid 0.137521 0.162921)
							(end 0.1016 0.1778)
						)
						(arc
							(start -0.1016 0.1778)
							(mid -0.137521 0.162921)
							(end -0.1524 0.127)
						)
						(arc
							(start -0.1524 -0.127)
							(mid -0.137521 -0.162921)
							(end -0.1016 -0.1778)
						)
						(arc
							(start 0.1016 -0.1778)
							(mid 0.137521 -0.162921)
							(end 0.1524 -0.127)
						)
					)
					(width 0)
					(fill yes)
				)
			)
		)
	)
	(footprint ""
		(layer "B.Cu")
		(at 181.051454 -49.597818 -90)
		(property "Reference" "C482"
			(at 0 0 90)
			(layer "B.SilkS")
			(hide yes)
			(effects
				(font
					(size 1.27 1.27)
				)
				(justify mirror)
			)
		)
		(property "Value" "SC1U16V2KX-7-GP"
			(at -1.7526 -1.6002 270)
			(unlocked yes)
			(layer "B.Fab")
			(hide yes)
			(effects
				(font
					(size 1.016 1.016)
					(thickness 0.1524)
				)
				(justify mirror)
			)
		)
		(property "Device Type" "C402-TO0D2H24"
			(at -1.7526 -3.1242 270)
			(unlocked yes)
			(layer "B.Fab")
			(hide yes)
			(effects
				(font
					(size 1.016 1.016)
					(thickness 0.1524)
				)
				(justify mirror)
			)
		)
		(duplicate_pad_numbers_are_jumpers no)
		(fp_rect
			(start 0.4826 0.889)
			(end -0.4826 -0.889)
			(stroke
				(width 0)
				(type default)
			)
			(fill no)
			(layer "B.CrtYd")
		)
		(fp_rect
			(start 0.4826 0.889)
			(end -0.4826 -0.889)
			(stroke
				(width 0)
				(type default)
			)
			(fill no)
			(layer "B.Fab")
		)
		(pad "1" smd custom
			(at 0 -0.4572 90)
			(size 0.1524 0.1524)
			(layers "B.Cu" "B.Mask" "B.Paste")
			(net "P1V8_C")
			(options
				(clearance outline)
				(anchor circle)
			)
			(primitives
				(gr_poly
					(pts
						(arc
							(start -0.254 -0.3048)
							(mid -0.325842 -0.275042)
							(end -0.3556 -0.2032)
						)
						(arc
							(start -0.3556 0.2032)
							(mid -0.325842 0.275042)
							(end -0.254 0.3048)
						)
						(arc
							(start 0.254 0.3048)
							(mid 0.325842 0.275042)
							(end 0.3556 0.2032)
						)
						(arc
							(start 0.3556 -0.2032)
							(mid 0.325842 -0.275042)
							(end 0.254 -0.3048)
						)
					)
					(width 0)
					(fill yes)
				)
			)
		)
		(pad "2" smd custom
			(at 0 0.4572 90)
			(size 0.1524 0.1524)
			(layers "B.Cu" "B.Mask" "B.Paste")
			(net "GND")
			(options
				(clearance outline)
				(anchor circle)
			)
			(primitives
				(gr_poly
					(pts
						(arc
							(start -0.254 -0.3048)
							(mid -0.325842 -0.275042)
							(end -0.3556 -0.2032)
						)
						(arc
							(start -0.3556 0.2032)
							(mid -0.325842 0.275042)
							(end -0.254 0.3048)
						)
						(arc
							(start 0.254 0.3048)
							(mid 0.325842 0.275042)
							(end 0.3556 0.2032)
						)
						(arc
							(start 0.3556 -0.2032)
							(mid 0.325842 -0.275042)
							(end 0.254 -0.3048)
						)
					)
					(width 0)
					(fill yes)
				)
			)
		)
	)
	(footprint ""
		(layer "B.Cu")
		(at 175.039528 -50.31613 180)
		(property "Reference" "C496"
			(at 0 0 0)
			(layer "B.SilkS")
			(hide yes)
			(effects
				(font
					(size 1.27 1.27)
				)
				(justify mirror)
			)
		)
		(property "Value" "SC1KP50V2KX-1GP"
			(at -1.1811 -2.7051 180)
			(unlocked yes)
			(layer "B.Fab")
			(hide yes)
			(effects
				(font
					(size 1.016 1.016)
					(thickness 0.1524)
				)
				(justify mirror)
			)
		)
		(property "Device Type" "C402H22"
			(at -1.1811 -4.2291 180)
			(unlocked yes)
			(layer "B.Fab")
			(hide yes)
			(effects
				(font
					(size 1.016 1.016)
					(thickness 0.1524)
				)
				(justify mirror)
			)
		)
		(duplicate_pad_numbers_are_jumpers no)
		(fp_rect
			(start 0.4318 0.9525)
			(end -0.4318 -0.9525)
			(stroke
				(width 0)
				(type default)
			)
			(fill no)
			(layer "B.CrtYd")
		)
		(fp_rect
			(start 0.4318 0.9525)
			(end -0.4318 -0.9525)
			(stroke
				(width 0)
				(type default)
			)
			(fill no)
			(layer "B.Fab")
		)
		(pad "1" smd custom
			(at 0 -0.4445)
			(size 0.1524 0.1524)
			(layers "B.Cu" "B.Mask" "B.Paste")
			(net "P1V8_C")
			(options
				(clearance outline)
				(anchor circle)
			)
			(primitives
				(gr_poly
					(pts
						(arc
							(start 0.3048 0.2032)
							(mid 0.275042 0.275042)
							(end 0.2032 0.3048)
						)
						(arc
							(start -0.2032 0.3048)
							(mid -0.275042 0.275042)
							(end -0.3048 0.2032)
						)
						(arc
							(start -0.3048 -0.2032)
							(mid -0.275042 -0.275042)
							(end -0.2032 -0.3048)
						)
						(arc
							(start 0.2032 -0.3048)
							(mid 0.275042 -0.275042)
							(end 0.3048 -0.2032)
						)
					)
					(width 0)
					(fill yes)
				)
			)
		)
		(pad "2" smd custom
			(at 0 0.4445)
			(size 0.1524 0.1524)
			(layers "B.Cu" "B.Mask" "B.Paste")
			(net "GND")
			(options
				(clearance outline)
				(anchor circle)
			)
			(primitives
				(gr_poly
					(pts
						(arc
							(start 0.3048 0.2032)
							(mid 0.275042 0.275042)
							(end 0.2032 0.3048)
						)
						(arc
							(start -0.2032 0.3048)
							(mid -0.275042 0.275042)
							(end -0.3048 0.2032)
						)
						(arc
							(start -0.3048 -0.2032)
							(mid -0.275042 -0.275042)
							(end -0.2032 -0.3048)
						)
						(arc
							(start 0.2032 -0.3048)
							(mid 0.275042 -0.275042)
							(end 0.3048 -0.2032)
						)
					)
					(width 0)
					(fill yes)
				)
			)
		)
	)
	(footprint ""
		(layer "B.Cu")
		(at 168.13403 -5.947156 90)
		(property "Reference" "C505"
			(at 0 0 90)
			(layer "B.SilkS")
			(hide yes)
			(effects
				(font
					(size 1.27 1.27)
				)
				(justify mirror)
			)
		)
		(property "Value" "SCD1U16V2KX-3GP"
			(at -1.1811 -2.7051 90)
			(unlocked yes)
			(layer "B.Fab")
			(hide yes)
			(effects
				(font
					(size 1.016 1.016)
					(thickness 0.1524)
				)
				(justify mirror)
			)
		)
		(property "Device Type" "C402H22"
			(at -1.1811 -4.2291 90)
			(unlocked yes)
			(layer "B.Fab")
			(hide yes)
			(effects
				(font
					(size 1.016 1.016)
					(thickness 0.1524)
				)
				(justify mirror)
			)
		)
		(duplicate_pad_numbers_are_jumpers no)
		(fp_rect
			(start 0.4318 0.9525)
			(end -0.4318 -0.9525)
			(stroke
				(width 0)
				(type default)
			)
			(fill no)
			(layer "B.CrtYd")
		)
		(fp_rect
			(start 0.4318 0.9525)
			(end -0.4318 -0.9525)
			(stroke
				(width 0)
				(type default)
			)
			(fill no)
			(layer "B.Fab")
		)
		(pad "1" smd custom
			(at 0 -0.4445 270)
			(size 0.1524 0.1524)
			(layers "B.Cu" "B.Mask" "B.Paste")
			(net "P1V8_E")
			(options
				(clearance outline)
				(anchor circle)
			)
			(primitives
				(gr_poly
					(pts
						(arc
							(start 0.3048 0.2032)
							(mid 0.275042 0.275042)
							(end 0.2032 0.3048)
						)
						(arc
							(start -0.2032 0.3048)
							(mid -0.275042 0.275042)
							(end -0.3048 0.2032)
						)
						(arc
							(start -0.3048 -0.2032)
							(mid -0.275042 -0.275042)
							(end -0.2032 -0.3048)
						)
						(arc
							(start 0.2032 -0.3048)
							(mid 0.275042 -0.275042)
							(end 0.3048 -0.2032)
						)
					)
					(width 0)
					(fill yes)
				)
			)
		)
		(pad "2" smd custom
			(at 0 0.4445 270)
			(size 0.1524 0.1524)
			(layers "B.Cu" "B.Mask" "B.Paste")
			(net "GND")
			(options
				(clearance outline)
				(anchor circle)
			)
			(primitives
				(gr_poly
					(pts
						(arc
							(start 0.3048 0.2032)
							(mid 0.275042 0.275042)
							(end 0.2032 0.3048)
						)
						(arc
							(start -0.2032 0.3048)
							(mid -0.275042 0.275042)
							(end -0.3048 0.2032)
						)
						(arc
							(start -0.3048 -0.2032)
							(mid -0.275042 -0.275042)
							(end -0.2032 -0.3048)
						)
						(arc
							(start 0.2032 -0.3048)
							(mid 0.275042 -0.275042)
							(end 0.3048 -0.2032)
						)
					)
					(width 0)
					(fill yes)
				)
			)
		)
	)
)
